(kicad_pcb
	(version 20260206)
	(generator "pcbnew")
	(generator_version "10.0")
	(general
		(thickness 1.6)
		(legacy_teardrops no)
	)
	(paper "A4")
	(title_block
		(title "Bryce Canyon_F.DPB_16315-1-OCP.brd")
		(comment 1 "Bryce Canyon / footprints 512-518 of 2223")
	)
	(layers
		(0 "F.Cu" signal "TOP")
		(4 "In1.Cu" signal "L2GND")
		(6 "In2.Cu" signal "L3")
		(8 "In3.Cu" signal "L4GND")
		(10 "In4.Cu" signal "L5")
		(12 "In5.Cu" signal "L6VCC")
		(14 "In6.Cu" signal "L7VCC")
		(16 "In7.Cu" signal "L8")
		(18 "In8.Cu" signal "L9GND")
		(20 "In9.Cu" signal "L10")
		(22 "In10.Cu" signal "L11GND")
		(2 "B.Cu" signal "BOTTOM")
		(9 "F.Adhes" user "F.Adhesive")
		(11 "B.Adhes" user "B.Adhesive")
		(13 "F.Paste" user "Package Geometry/Pastemask Top")
		(15 "B.Paste" user "Package Geometry/Pastemask Bottom")
		(5 "F.SilkS" user "Ref Des/Silkscreen Top")
		(7 "B.SilkS" user "Ref Des/Silkscreen Bottom")
		(1 "F.Mask" user "Board Geometry/Soldermask Top")
		(3 "B.Mask" user "Board Geometry/Soldermask Bottom")
		(17 "Dwgs.User" user "User.Drawings")
		(19 "Cmts.User" user "User.Comments")
		(21 "Eco1.User" user "User.Eco1")
		(23 "Eco2.User" user "User.Eco2")
		(25 "Edge.Cuts" user "Board Geometry/Outline")
		(27 "Margin" user)
		(31 "F.CrtYd" user "Package Geometry/Place Bound Top")
		(29 "B.CrtYd" user "Package Geometry/Place Bound Bottom")
		(35 "F.Fab" user "Ref Des/Assembly Top")
		(33 "B.Fab" user "Ref Des/Assembly Bottom")
	)
	(footprint ""
		(layer "F.Cu")
		(at 334.6196 -272.5928 180)
		(property "Reference" "R279"
			(at 0 0 180)
			(layer "F.SilkS")
			(hide yes)
			(effects
				(font
					(size 1.27 1.27)
				)
			)
		)
		(property "Value" "0R2J-2-GP"
			(at 0.064008 -3.993896 180)
			(unlocked yes)
			(layer "F.Fab")
			(hide yes)
			(effects
				(font
					(size 1.016 1.016)
					(thickness 0.1524)
				)
			)
		)
		(property "Device Type" "R402H16"
			(at 0.064008 -5.517896 180)
			(unlocked yes)
			(layer "F.Fab")
			(hide yes)
			(effects
				(font
					(size 1.016 1.016)
					(thickness 0.1524)
				)
			)
		)
		(duplicate_pad_numbers_are_jumpers no)
		(fp_line
			(start 0.508 -0.9398)
			(end -0.508 -0.9398)
			(stroke
				(width 0.1524)
				(type default)
			)
			(layer "F.SilkS")
		)
		(fp_line
			(start -0.508 -0.9398)
			(end -0.508 0.9398)
			(stroke
				(width 0.1524)
				(type default)
			)
			(layer "F.SilkS")
		)
		(fp_rect
			(start -0.508 0.9398)
			(end 0.508 -0.9398)
			(stroke
				(width 0)
				(type default)
			)
			(fill no)
			(layer "F.CrtYd")
		)
		(fp_rect
			(start -0.508 0.9398)
			(end 0.508 -0.9398)
			(stroke
				(width 0)
				(type default)
			)
			(fill no)
			(layer "F.Fab")
		)
		(pad "1" smd custom
			(at 0 -0.4445 180)
			(size 0.1397 0.1397)
			(layers "F.Cu" "F.Mask" "F.Paste")
			(net "DRIVE_A_6_PWR")
			(options
				(clearance outline)
				(anchor circle)
			)
			(primitives
				(gr_poly
					(pts
						(arc
							(start -0.1778 -0.2794)
							(mid -0.249642 -0.249642)
							(end -0.2794 -0.1778)
						)
						(arc
							(start -0.2794 0.1778)
							(mid -0.249642 0.249642)
							(end -0.1778 0.2794)
						)
						(arc
							(start 0.1778 0.2794)
							(mid 0.249642 0.249642)
							(end 0.2794 0.1778)
						)
						(arc
							(start 0.2794 -0.1778)
							(mid 0.249642 -0.249642)
							(end 0.1778 -0.2794)
						)
					)
					(width 0)
					(fill yes)
				)
			)
		)
		(pad "2" smd custom
			(at 0 0.4445 180)
			(size 0.1397 0.1397)
			(layers "F.Cu" "F.Mask" "F.Paste")
			(net "SW_PWR_R_HDD6")
			(options
				(clearance outline)
				(anchor circle)
			)
			(primitives
				(gr_poly
					(pts
						(arc
							(start -0.1778 -0.2794)
							(mid -0.249642 -0.249642)
							(end -0.2794 -0.1778)
						)
						(arc
							(start -0.2794 0.1778)
							(mid -0.249642 0.249642)
							(end -0.1778 0.2794)
						)
						(arc
							(start 0.1778 0.2794)
							(mid 0.249642 0.249642)
							(end 0.2794 0.1778)
						)
						(arc
							(start 0.2794 -0.1778)
							(mid 0.249642 -0.249642)
							(end 0.1778 -0.2794)
						)
					)
					(width 0)
					(fill yes)
				)
			)
		)
	)
	(footprint ""
		(layer "F.Cu")
		(at 271.0688 -12.4206 90)
		(property "Reference" "TP195"
			(at 0 0 90)
			(layer "F.SilkS")
			(hide yes)
			(effects
				(font
					(size 1.27 1.27)
				)
			)
		)
		(property "Value" "TPAD32-GP"
			(at -0.0508 -1.6764 90)
			(unlocked yes)
			(layer "F.Fab")
			(hide yes)
			(effects
				(font
					(size 1.016 1.016)
					(thickness 0.1524)
				)
			)
		)
		(property "Device Type" "TPAD32"
			(at -0.0508 -3.2004 90)
			(unlocked yes)
			(layer "F.Fab")
			(hide yes)
			(effects
				(font
					(size 1.016 1.016)
					(thickness 0.1524)
				)
			)
		)
		(duplicate_pad_numbers_are_jumpers no)
		(fp_poly
			(pts
				(arc
					(start 0 0.4064)
					(mid 0 -0.4064)
					(end 0 0.4064)
				)
			)
			(stroke
				(width 0)
				(type default)
			)
			(fill no)
			(layer "F.CrtYd")
		)
		(fp_poly
			(pts
				(arc
					(start 0 0.7112)
					(mid 0 -0.7112)
					(end 0 0.7112)
				)
			)
			(stroke
				(width 0)
				(type default)
			)
			(fill no)
			(layer "F.Fab")
		)
		(pad "1" smd circle
			(at 0 0 90)
			(size 0.8128 0.8128)
			(layers "F.Cu" "F.Mask" "F.Paste")
			(net "TP_COMP_B_NCSI_CRSDV")
		)
	)
	(footprint ""
		(layer "F.Cu")
		(at 446.1891 -273.940016 90)
		(property "Reference" "VIA5"
			(at 0 0 90)
			(layer "F.SilkS")
			(hide yes)
			(effects
				(font
					(size 1.27 1.27)
				)
			)
		)
		(property "Value" "100OHM-8L-1D6MM-L18L16-GP"
			(at -3.7211 -4.5085 90)
			(unlocked yes)
			(layer "F.Fab")
			(hide yes)
			(effects
				(font
					(size 1.016 1.016)
					(thickness 0.1524)
				)
			)
		)
		(property "Device Type" "VIA-PCIE-4P-394076"
			(at -3.7211 -6.0325 90)
			(unlocked yes)
			(layer "F.Fab")
			(hide yes)
			(effects
				(font
					(size 1.016 1.016)
					(thickness 0.1524)
				)
			)
		)
		(duplicate_pad_numbers_are_jumpers no)
		(fp_rect
			(start -1.9685 0.381)
			(end 1.9685 -0.381)
			(stroke
				(width 0)
				(type default)
			)
			(fill no)
			(layer "F.CrtYd")
		)
		(fp_rect
			(start -1.9685 0.381)
			(end 1.9685 -0.381)
			(stroke
				(width 0)
				(type default)
			)
			(fill no)
			(layer "F.Fab")
		)
		(pad "1" thru_hole circle
			(at -1.5875 0 90)
			(size 0.508 0.508)
			(drill 0.254)
			(layers "*.Cu" "*.Mask")
			(remove_unused_layers no)
			(net "GND")
			(clearance 0.127)
			(thermal_gap 0.127)
		)
		(pad "2" thru_hole circle
			(at -0.5715 0 90)
			(size 0.508 0.508)
			(drill 0.254)
			(layers "*.Cu" "*.Mask")
			(remove_unused_layers no)
			(net "PHY_SCC_A_TO_DRV_A_10_DP")
			(clearance 0.127)
			(thermal_gap 0.127)
		)
		(pad "3" thru_hole circle
			(at 0.5715 0 90)
			(size 0.508 0.508)
			(drill 0.254)
			(layers "*.Cu" "*.Mask")
			(remove_unused_layers no)
			(net "PHY_SCC_A_TO_DRV_A_10_DN")
			(clearance 0.127)
			(thermal_gap 0.127)
		)
		(pad "4" thru_hole circle
			(at 1.5875 0 90)
			(size 0.508 0.508)
			(drill 0.254)
			(layers "*.Cu" "*.Mask")
			(remove_unused_layers no)
			(net "GND")
			(clearance 0.127)
			(thermal_gap 0.127)
		)
	)
	(footprint ""
		(layer "F.Cu")
		(at 395.83995 -49.596294 90)
		(property "Reference" "C464"
			(at 0 0 90)
			(layer "F.SilkS")
			(hide yes)
			(effects
				(font
					(size 1.27 1.27)
				)
			)
		)
		(property "Value" "SCD033U25V2KX-GP"
			(at 1.1811 -2.7051 90)
			(unlocked yes)
			(layer "F.Fab")
			(hide yes)
			(effects
				(font
					(size 1.016 1.016)
					(thickness 0.1524)
				)
			)
		)
		(property "Device Type" "C402H22"
			(at 1.1811 -4.2291 90)
			(unlocked yes)
			(layer "F.Fab")
			(hide yes)
			(effects
				(font
					(size 1.016 1.016)
					(thickness 0.1524)
				)
			)
		)
		(duplicate_pad_numbers_are_jumpers no)
		(fp_rect
			(start -0.4318 0.9525)
			(end 0.4318 -0.9525)
			(stroke
				(width 0)
				(type default)
			)
			(fill no)
			(layer "F.CrtYd")
		)
		(fp_rect
			(start -0.4318 0.9525)
			(end 0.4318 -0.9525)
			(stroke
				(width 0)
				(type default)
			)
			(fill no)
			(layer "F.Fab")
		)
		(pad "1" smd custom
			(at 0 -0.4445 90)
			(size 0.1524 0.1524)
			(layers "F.Cu" "F.Mask" "F.Paste")
			(net "SW_HDD_P32")
			(options
				(clearance outline)
				(anchor circle)
			)
			(primitives
				(gr_poly
					(pts
						(arc
							(start 0.3048 -0.2032)
							(mid 0.275042 -0.275042)
							(end 0.2032 -0.3048)
						)
						(arc
							(start -0.2032 -0.3048)
							(mid -0.275042 -0.275042)
							(end -0.3048 -0.2032)
						)
						(arc
							(start -0.3048 0.2032)
							(mid -0.275042 0.275042)
							(end -0.2032 0.3048)
						)
						(arc
							(start 0.2032 0.3048)
							(mid 0.275042 0.275042)
							(end 0.3048 0.2032)
						)
					)
					(width 0)
					(fill yes)
				)
			)
		)
		(pad "2" smd custom
			(at 0 0.4445 90)
			(size 0.1524 0.1524)
			(layers "F.Cu" "F.Mask" "F.Paste")
			(net "GND")
			(options
				(clearance outline)
				(anchor circle)
			)
			(primitives
				(gr_poly
					(pts
						(arc
							(start 0.3048 -0.2032)
							(mid 0.275042 -0.275042)
							(end 0.2032 -0.3048)
						)
						(arc
							(start -0.2032 -0.3048)
							(mid -0.275042 -0.275042)
							(end -0.3048 -0.2032)
						)
						(arc
							(start -0.3048 0.2032)
							(mid -0.275042 0.275042)
							(end -0.2032 0.3048)
						)
						(arc
							(start 0.2032 0.3048)
							(mid 0.275042 0.275042)
							(end 0.3048 0.2032)
						)
					)
					(width 0)
					(fill yes)
				)
			)
		)
	)
	(footprint ""
		(layer "F.Cu")
		(at 434.168042 -130.336036 -90)
		(property "Reference" "R542"
			(at 0 0 270)
			(layer "F.SilkS")
			(hide yes)
			(effects
				(font
					(size 1.27 1.27)
				)
			)
		)
		(property "Value" "4K7R2J-2-GP"
			(at 0.064008 -3.993896 270)
			(unlocked yes)
			(layer "F.Fab")
			(hide yes)
			(effects
				(font
					(size 1.016 1.016)
					(thickness 0.1524)
				)
			)
		)
		(property "Device Type" "R402H16"
			(at 0.064008 -5.517896 270)
			(unlocked yes)
			(layer "F.Fab")
			(hide yes)
			(effects
				(font
					(size 1.016 1.016)
					(thickness 0.1524)
				)
			)
		)
		(duplicate_pad_numbers_are_jumpers no)
		(fp_line
			(start -0.508 -0.9398)
			(end -0.508 0.9398)
			(stroke
				(width 0.1524)
				(type default)
			)
			(layer "F.SilkS")
		)
		(fp_line
			(start 0.508 -0.9398)
			(end -0.508 -0.9398)
			(stroke
				(width 0.1524)
				(type default)
			)
			(layer "F.SilkS")
		)
		(fp_rect
			(start -0.508 0.9398)
			(end 0.508 -0.9398)
			(stroke
				(width 0)
				(type default)
			)
			(fill no)
			(layer "F.CrtYd")
		)
		(fp_rect
			(start -0.508 0.9398)
			(end 0.508 -0.9398)
			(stroke
				(width 0)
				(type default)
			)
			(fill no)
			(layer "F.Fab")
		)
		(pad "1" smd custom
			(at 0 -0.4445 270)
			(size 0.1397 0.1397)
			(layers "F.Cu" "F.Mask" "F.Paste")
			(net "DRIVE_A_22_ACT")
			(options
				(clearance outline)
				(anchor circle)
			)
			(primitives
				(gr_poly
					(pts
						(arc
							(start -0.1778 -0.2794)
							(mid -0.249642 -0.249642)
							(end -0.2794 -0.1778)
						)
						(arc
							(start -0.2794 0.1778)
							(mid -0.249642 0.249642)
							(end -0.1778 0.2794)
						)
						(arc
							(start 0.1778 0.2794)
							(mid 0.249642 0.249642)
							(end 0.2794 0.1778)
						)
						(arc
							(start 0.2794 -0.1778)
							(mid 0.249642 -0.249642)
							(end 0.1778 -0.2794)
						)
					)
					(width 0)
					(fill yes)
				)
			)
		)
		(pad "2" smd custom
			(at 0 0.4445 270)
			(size 0.1397 0.1397)
			(layers "F.Cu" "F.Mask" "F.Paste")
			(net "GND")
			(options
				(clearance outline)
				(anchor circle)
			)
			(primitives
				(gr_poly
					(pts
						(arc
							(start -0.1778 -0.2794)
							(mid -0.249642 -0.249642)
							(end -0.2794 -0.1778)
						)
						(arc
							(start -0.2794 0.1778)
							(mid -0.249642 0.249642)
							(end -0.1778 0.2794)
						)
						(arc
							(start 0.1778 0.2794)
							(mid 0.249642 0.249642)
							(end 0.2794 0.1778)
						)
						(arc
							(start 0.2794 -0.1778)
							(mid 0.249642 -0.249642)
							(end 0.1778 -0.2794)
						)
					)
					(width 0)
					(fill yes)
				)
			)
		)
	)
	(footprint ""
		(layer "F.Cu")
		(at 113.065052 -242.25377)
		(property "Reference" "R220"
			(at 0 0 0)
			(layer "F.SilkS")
			(hide yes)
			(effects
				(font
					(size 1.27 1.27)
				)
			)
		)
		(property "Value" "91R3F-1-GP"
			(at -0.0254 -2.5146 0)
			(unlocked yes)
			(layer "F.Fab")
			(hide yes)
			(effects
				(font
					(size 1.016 1.016)
					(thickness 0.1524)
				)
			)
		)
		(property "Device Type" "R603H22"
			(at -0.0254 -4.0386 0)
			(unlocked yes)
			(layer "F.Fab")
			(hide yes)
			(effects
				(font
					(size 1.016 1.016)
					(thickness 0.1524)
				)
			)
		)
		(duplicate_pad_numbers_are_jumpers no)
		(fp_line
			(start -0.4826 0)
			(end -0.2032 0)
			(stroke
				(width 0.2032)
				(type default)
			)
			(layer "F.SilkS")
		)
		(fp_line
			(start 0.2032 0)
			(end 0.4826 0)
			(stroke
				(width 0.2032)
				(type default)
			)
			(layer "F.SilkS")
		)
		(fp_rect
			(start -0.5842 1.3335)
			(end 0.5842 -1.3335)
			(stroke
				(width 0)
				(type default)
			)
			(fill no)
			(layer "F.CrtYd")
		)
		(fp_rect
			(start -0.5842 1.3335)
			(end 0.5842 -1.3335)
			(stroke
				(width 0)
				(type default)
			)
			(fill no)
			(layer "F.Fab")
		)
		(pad "1" smd custom
			(at 0 -0.762)
			(size 0.2159 0.2159)
			(layers "F.Cu" "F.Mask" "F.Paste")
			(net "P5V_A_1")
			(options
				(clearance outline)
				(anchor circle)
			)
			(primitives
				(gr_poly
					(pts
						(arc
							(start -0.3302 -0.4318)
							(mid -0.402042 -0.402042)
							(end -0.4318 -0.3302)
						)
						(arc
							(start -0.4318 0.3302)
							(mid -0.402042 0.402042)
							(end -0.3302 0.4318)
						)
						(arc
							(start 0.3302 0.4318)
							(mid 0.402042 0.402042)
							(end 0.4318 0.3302)
						)
						(arc
							(start 0.4318 -0.3302)
							(mid 0.402042 -0.402042)
							(end 0.3302 -0.4318)
						)
					)
					(width 0)
					(fill yes)
				)
			)
		)
		(pad "2" smd custom
			(at 0 0.762)
			(size 0.2159 0.2159)
			(layers "F.Cu" "F.Mask" "F.Paste")
			(net "DRV_ACT_3")
			(options
				(clearance outline)
				(anchor circle)
			)
			(primitives
				(gr_poly
					(pts
						(arc
							(start -0.3302 -0.4318)
							(mid -0.402042 -0.402042)
							(end -0.4318 -0.3302)
						)
						(arc
							(start -0.4318 0.3302)
							(mid -0.402042 0.402042)
							(end -0.3302 0.4318)
						)
						(arc
							(start 0.3302 0.4318)
							(mid 0.402042 0.402042)
							(end 0.4318 0.3302)
						)
						(arc
							(start 0.4318 -0.3302)
							(mid 0.402042 -0.402042)
							(end 0.3302 -0.4318)
						)
					)
					(width 0)
					(fill yes)
				)
			)
		)
	)
	(footprint ""
		(layer "F.Cu")
		(at 429.549052 -52.872894 -90)
		(property "Reference" "Q197"
			(at 0 0 270)
			(layer "F.SilkS")
			(hide yes)
			(effects
				(font
					(size 1.27 1.27)
				)
			)
		)
		(property "Value" "AO4406AL-GP"
			(at -3.707384 -1.5367 270)
			(unlocked yes)
			(layer "F.Fab")
			(hide yes)
			(effects
				(font
					(size 1.016 1.016)
					(thickness 0.1524)
				)
			)
		)
		(property "Device Type" "SOIC8H69"
			(at -3.707384 -3.0607 270)
			(unlocked yes)
			(layer "F.Fab")
			(hide yes)
			(effects
				(font
					(size 1.016 1.016)
					(thickness 0.1524)
				)
			)
		)
		(duplicate_pad_numbers_are_jumpers no)
		(fp_line
			(start -2.6289 3.4417)
			(end -2.6289 1.4732)
			(stroke
				(width 0.381)
				(type default)
			)
			(layer "F.SilkS")
		)
		(fp_line
			(start -2.7432 1.4224)
			(end -2.6416 1.4224)
			(stroke
				(width 0.1524)
				(type default)
			)
			(layer "F.SilkS")
		)
		(fp_line
			(start -2.7432 1.4224)
			(end 2.1336 1.4224)
			(stroke
				(width 0.1524)
				(type default)
			)
			(layer "F.SilkS")
		)
		(fp_line
			(start 2.1336 1.4224)
			(end 2.1336 -1.4224)
			(stroke
				(width 0.1524)
				(type default)
			)
			(layer "F.SilkS")
		)
		(fp_line
			(start -2.1844 -0.0508)
			(end -2.7178 0.508)
			(stroke
				(width 0.1524)
				(type default)
			)
			(layer "F.SilkS")
		)
		(fp_line
			(start -2.7178 -0.508)
			(end -2.1844 -0.0508)
			(stroke
				(width 0.1524)
				(type default)
			)
			(layer "F.SilkS")
		)
		(fp_line
			(start -2.7432 -1.4224)
			(end -2.7432 1.4224)
			(stroke
				(width 0.1524)
				(type default)
			)
			(layer "F.SilkS")
		)
		(fp_line
			(start 2.1336 -1.4224)
			(end -2.7432 -1.4224)
			(stroke
				(width 0.1524)
				(type default)
			)
			(layer "F.SilkS")
		)
		(fp_poly
			(pts
				(xy -2.2098 -1.4224) (xy -2.2098 1.4224) (xy 2.2098 1.4224) (xy 2.2098 -1.4224)
			)
			(stroke
				(width 0)
				(type default)
			)
			(fill yes)
			(layer "F.SilkS")
		)
		(fp_rect
			(start -2.450084 2.999994)
			(end 2.450084 -2.999994)
			(stroke
				(width 0)
				(type default)
			)
			(fill no)
			(layer "F.CrtYd")
		)
		(fp_poly
			(pts
				(xy -2.8194 3.6322) (xy -2.8194 -3.6322) (xy 2.8194 -3.6322) (xy 2.8194 1.18364) (xy 2.450084 1.18364)
				(xy 2.450084 -2.999994) (xy -2.450084 -2.999994) (xy -2.450084 2.999994) (xy 2.450084 2.999994)
				(xy 2.450084 1.18618) (xy 2.8194 1.18618) (xy 2.8194 3.6322)
			)
			(stroke
				(width 0)
				(type default)
			)
			(fill no)
			(layer "F.CrtYd")
		)
		(fp_rect
			(start -2.8194 3.6322)
			(end 2.8194 -3.6322)
			(stroke
				(width 0)
				(type default)
			)
			(fill no)
			(layer "F.Fab")
		)
		(pad "1" smd rect
			(at -1.905 2.54 270)
			(size 0.635 1.651)
			(layers "F.Cu" "F.Mask" "F.Paste")
			(net "P5V_HDD33")
		)
		(pad "2" smd rect
			(at -0.635 2.54 270)
			(size 0.635 1.651)
			(layers "F.Cu" "F.Mask" "F.Paste")
			(net "P5V_HDD33")
		)
		(pad "3" smd rect
			(at 0.635 2.54 270)
			(size 0.635 1.651)
			(layers "F.Cu" "F.Mask" "F.Paste")
			(net "P5V_HDD33")
		)
		(pad "4" smd rect
			(at 1.905 2.54 270)
			(size 0.635 1.651)
			(layers "F.Cu" "F.Mask" "F.Paste")
			(net "SW_HDD_P33")
		)
		(pad "5" smd rect
			(at 1.905 -2.54 270)
			(size 0.635 1.651)
			(layers "F.Cu" "F.Mask" "F.Paste")
			(net "P5V_A_4")
		)
		(pad "6" smd rect
			(at 0.635 -2.54 270)
			(size 0.635 1.651)
			(layers "F.Cu" "F.Mask" "F.Paste")
			(net "P5V_A_4")
		)
		(pad "7" smd rect
			(at -0.635 -2.54 270)
			(size 0.635 1.651)
			(layers "F.Cu" "F.Mask" "F.Paste")
			(net "P5V_A_4")
		)
		(pad "8" smd rect
			(at -1.905 -2.54 270)
			(size 0.635 1.651)
			(layers "F.Cu" "F.Mask" "F.Paste")
			(net "P5V_A_4")
		)
	)
)
